(kicad_pcb
	(version 20260206)
	(generator "pcbnew")
	(generator_version "10.0")
	(general
		(thickness 1.6)
		(legacy_teardrops no)
	)
	(paper "A4")
	(title_block
		(title "03242023_DA0F0TMBIJ0_F0T_Motherboard_J_brd_V01_OCP.brd")
		(comment 1 "Grand Teton / footprints 5348-5354 of 6105")
	)
	(layers
		(0 "F.Cu" signal "TOP")
		(4 "In1.Cu" signal "GND")
		(6 "In2.Cu" signal "IN1")
		(8 "In3.Cu" signal "GND1")
		(10 "In4.Cu" signal "IN2")
		(12 "In5.Cu" signal "GND2")
		(14 "In6.Cu" signal "IN3")
		(16 "In7.Cu" signal "GND3")
		(18 "In8.Cu" signal "VCC")
		(20 "In9.Cu" signal "VCC1")
		(22 "In10.Cu" signal "GND4")
		(24 "In11.Cu" signal "IN4")
		(26 "In12.Cu" signal "GND5")
		(28 "In13.Cu" signal "IN5")
		(30 "In14.Cu" signal "GND6")
		(32 "In15.Cu" signal "IN6")
		(34 "In16.Cu" signal "GND7")
		(2 "B.Cu" signal "BOTTOM")
		(9 "F.Adhes" user "F.Adhesive")
		(11 "B.Adhes" user "B.Adhesive")
		(13 "F.Paste" user "Package Geometry/Pastemask Top")
		(15 "B.Paste" user "Package Geometry/Pastemask Bottom")
		(5 "F.SilkS" user "Ref Des/Silkscreen Top")
		(7 "B.SilkS" user "Ref Des/Silkscreen Bottom")
		(1 "F.Mask" user "Board Geometry/Soldermask Top")
		(3 "B.Mask" user "Board Geometry/Soldermask Bottom")
		(17 "Dwgs.User" user "User.Drawings")
		(19 "Cmts.User" user "User.Comments")
		(21 "Eco1.User" user "User.Eco1")
		(23 "Eco2.User" user "User.Eco2")
		(25 "Edge.Cuts" user "Board Geometry/Outline")
		(27 "Margin" user)
		(31 "F.CrtYd" user "Package Geometry/Place Bound Top")
		(29 "B.CrtYd" user "Package Geometry/Place Bound Bottom")
		(35 "F.Fab" user "Ref Des/Assembly Top")
		(33 "B.Fab" user "Ref Des/Assembly Bottom")
	)
	(footprint ""
		(layer "B.Cu")
		(at 404.006812 -52.722018 180)
		(property "Reference" "R772"
			(at 0 0 0)
			(layer "B.SilkS")
			(hide yes)
			(effects
				(font
					(size 1.27 1.27)
				)
				(justify mirror)
			)
		)
		(property "Value" ""
			(at 0 0 0)
			(layer "B.Fab")
			(effects
				(font
					(size 1.27 1.27)
				)
				(justify mirror)
			)
		)
		(duplicate_pad_numbers_are_jumpers no)
		(fp_line
			(start 0.7874 0.4064)
			(end 0.7874 -0.4064)
			(stroke
				(width 0.1524)
				(type default)
			)
			(layer "B.SilkS")
		)
		(fp_line
			(start 0.7874 -0.4064)
			(end -0.7874 -0.4064)
			(stroke
				(width 0.1524)
				(type default)
			)
			(layer "B.SilkS")
		)
		(fp_line
			(start -0.7874 0.4064)
			(end 0.7874 0.4064)
			(stroke
				(width 0.1524)
				(type default)
			)
			(layer "B.SilkS")
		)
		(fp_line
			(start -0.7874 -0.4064)
			(end -0.7874 0.4064)
			(stroke
				(width 0.1524)
				(type default)
			)
			(layer "B.SilkS")
		)
		(fp_line
			(start 0.67945 0.3048)
			(end 0.67945 -0.305054)
			(stroke
				(width 0.1)
				(type default)
			)
			(layer "B.Fab")
		)
		(fp_line
			(start 0.67945 -0.305054)
			(end 0.12065 -0.305054)
			(stroke
				(width 0.1)
				(type default)
			)
			(layer "B.Fab")
		)
		(fp_line
			(start 0.12065 0.3048)
			(end 0.67945 0.3048)
			(stroke
				(width 0.1)
				(type default)
			)
			(layer "B.Fab")
		)
		(fp_line
			(start 0.12065 0.2794)
			(end 0.12065 0.3048)
			(stroke
				(width 0.1)
				(type default)
			)
			(layer "B.Fab")
		)
		(fp_line
			(start 0.12065 -0.2794)
			(end -0.12065 -0.2794)
			(stroke
				(width 0.1)
				(type default)
			)
			(layer "B.Fab")
		)
		(fp_line
			(start 0.12065 -0.305054)
			(end 0.12065 -0.2794)
			(stroke
				(width 0.1)
				(type default)
			)
			(layer "B.Fab")
		)
		(fp_line
			(start -0.120396 0.3048)
			(end -0.120396 0.2794)
			(stroke
				(width 0.1)
				(type default)
			)
			(layer "B.Fab")
		)
		(fp_line
			(start -0.120396 0.2794)
			(end 0.12065 0.2794)
			(stroke
				(width 0.1)
				(type default)
			)
			(layer "B.Fab")
		)
		(fp_line
			(start -0.12065 -0.2794)
			(end -0.12065 -0.3048)
			(stroke
				(width 0.1)
				(type default)
			)
			(layer "B.Fab")
		)
		(fp_line
			(start -0.12065 -0.3048)
			(end -0.67945 -0.3048)
			(stroke
				(width 0.1)
				(type default)
			)
			(layer "B.Fab")
		)
		(fp_line
			(start -0.67945 0.3048)
			(end -0.120396 0.3048)
			(stroke
				(width 0.1)
				(type default)
			)
			(layer "B.Fab")
		)
		(fp_line
			(start -0.67945 -0.3048)
			(end -0.67945 0.3048)
			(stroke
				(width 0.1)
				(type default)
			)
			(layer "B.Fab")
		)
		(pad "1" smd circle
			(at 0.40005 0)
			(size 0 0)
			(layers "B.Cu" "B.Mask" "B.Paste")
			(net "JTAG_RST_DBP_RSMRST_N")
		)
		(pad "2" smd circle
			(at -0.40005 0)
			(size 0 0)
			(layers "B.Cu" "B.Mask" "B.Paste")
			(net "RST_RSMRST_PCH_N")
		)
	)
	(footprint ""
		(layer "B.Cu")
		(at 290.332414 -321.549776 -90)
		(property "Reference" "C10"
			(at 0 0 90)
			(layer "B.SilkS")
			(hide yes)
			(effects
				(font
					(size 1.27 1.27)
				)
				(justify mirror)
			)
		)
		(property "Value" ""
			(at 0 0 90)
			(layer "B.Fab")
			(effects
				(font
					(size 1.27 1.27)
				)
				(justify mirror)
			)
		)
		(duplicate_pad_numbers_are_jumpers no)
		(fp_line
			(start -1.524 0.762)
			(end 1.524 0.762)
			(stroke
				(width 0.1524)
				(type default)
			)
			(layer "B.SilkS")
		)
		(fp_line
			(start 1.524 0.762)
			(end 1.524 -0.762)
			(stroke
				(width 0.1524)
				(type default)
			)
			(layer "B.SilkS")
		)
		(fp_line
			(start -1.524 -0.762)
			(end -1.524 0.762)
			(stroke
				(width 0.1524)
				(type default)
			)
			(layer "B.SilkS")
		)
		(fp_line
			(start 1.524 -0.762)
			(end -1.524 -0.762)
			(stroke
				(width 0.1524)
				(type default)
			)
			(layer "B.SilkS")
		)
		(fp_line
			(start -1.1049 0.724916)
			(end -1.1049 -0.724916)
			(stroke
				(width 0.1)
				(type default)
			)
			(layer "B.Fab")
		)
		(fp_line
			(start 1.1049 0.724916)
			(end -1.1049 0.724916)
			(stroke
				(width 0.1)
				(type default)
			)
			(layer "B.Fab")
		)
		(fp_line
			(start -1.1049 -0.724916)
			(end 1.1049 -0.724916)
			(stroke
				(width 0.1)
				(type default)
			)
			(layer "B.Fab")
		)
		(fp_line
			(start 1.1049 -0.724916)
			(end 1.1049 0.724916)
			(stroke
				(width 0.1)
				(type default)
			)
			(layer "B.Fab")
		)
		(pad "1" smd rect
			(at 0.889 0 270)
			(size 1.016 1.27)
			(layers "B.Cu" "B.Mask" "B.Paste")
			(net "P12V_S3_AUX_CPU0_NVDIMM")
		)
		(pad "2" smd rect
			(at -0.889 0 270)
			(size 1.016 1.27)
			(layers "B.Cu" "B.Mask" "B.Paste")
			(net "GND")
		)
	)
	(footprint ""
		(layer "B.Cu")
		(at 366.120934 -255.853946 -90)
		(property "Reference" "C358"
			(at 0 0 90)
			(layer "B.SilkS")
			(hide yes)
			(effects
				(font
					(size 1.27 1.27)
				)
				(justify mirror)
			)
		)
		(property "Value" ""
			(at 0 0 90)
			(layer "B.Fab")
			(effects
				(font
					(size 1.27 1.27)
				)
				(justify mirror)
			)
		)
		(duplicate_pad_numbers_are_jumpers no)
		(fp_line
			(start -1.524 0.762)
			(end 1.524 0.762)
			(stroke
				(width 0.1524)
				(type default)
			)
			(layer "B.SilkS")
		)
		(fp_line
			(start 1.524 0.762)
			(end 1.524 -0.762)
			(stroke
				(width 0.1524)
				(type default)
			)
			(layer "B.SilkS")
		)
		(fp_line
			(start -1.524 -0.762)
			(end -1.524 0.762)
			(stroke
				(width 0.1524)
				(type default)
			)
			(layer "B.SilkS")
		)
		(fp_line
			(start 1.524 -0.762)
			(end -1.524 -0.762)
			(stroke
				(width 0.1524)
				(type default)
			)
			(layer "B.SilkS")
		)
		(fp_line
			(start -1.1049 0.724916)
			(end -1.1049 -0.724916)
			(stroke
				(width 0.1)
				(type default)
			)
			(layer "B.Fab")
		)
		(fp_line
			(start 1.1049 0.724916)
			(end -1.1049 0.724916)
			(stroke
				(width 0.1)
				(type default)
			)
			(layer "B.Fab")
		)
		(fp_line
			(start -1.1049 -0.724916)
			(end 1.1049 -0.724916)
			(stroke
				(width 0.1)
				(type default)
			)
			(layer "B.Fab")
		)
		(fp_line
			(start 1.1049 -0.724916)
			(end 1.1049 0.724916)
			(stroke
				(width 0.1)
				(type default)
			)
			(layer "B.Fab")
		)
		(pad "1" smd rect
			(at 0.889 0 270)
			(size 1.016 1.27)
			(layers "B.Cu" "B.Mask" "B.Paste")
			(net "PVCCIN_CPU0")
		)
		(pad "2" smd rect
			(at -0.889 0 270)
			(size 1.016 1.27)
			(layers "B.Cu" "B.Mask" "B.Paste")
			(net "GND")
		)
	)
	(footprint ""
		(layer "B.Cu")
		(at 327.613518 -188.61278 90)
		(property "Reference" "R744"
			(at 0 0 90)
			(layer "B.SilkS")
			(hide yes)
			(effects
				(font
					(size 1.27 1.27)
				)
				(justify mirror)
			)
		)
		(property "Value" ""
			(at 0 0 90)
			(layer "B.Fab")
			(effects
				(font
					(size 1.27 1.27)
				)
				(justify mirror)
			)
		)
		(duplicate_pad_numbers_are_jumpers no)
		(fp_line
			(start 0.7874 -0.4064)
			(end -0.7874 -0.4064)
			(stroke
				(width 0.1524)
				(type default)
			)
			(layer "B.SilkS")
		)
		(fp_line
			(start -0.7874 -0.4064)
			(end -0.7874 0.4064)
			(stroke
				(width 0.1524)
				(type default)
			)
			(layer "B.SilkS")
		)
		(fp_line
			(start 0.7874 0.4064)
			(end 0.7874 -0.4064)
			(stroke
				(width 0.1524)
				(type default)
			)
			(layer "B.SilkS")
		)
		(fp_line
			(start -0.7874 0.4064)
			(end 0.7874 0.4064)
			(stroke
				(width 0.1524)
				(type default)
			)
			(layer "B.SilkS")
		)
		(fp_line
			(start 0.67945 -0.305054)
			(end 0.12065 -0.305054)
			(stroke
				(width 0.1)
				(type default)
			)
			(layer "B.Fab")
		)
		(fp_line
			(start 0.12065 -0.305054)
			(end 0.12065 -0.2794)
			(stroke
				(width 0.1)
				(type default)
			)
			(layer "B.Fab")
		)
		(fp_line
			(start -0.12065 -0.3048)
			(end -0.67945 -0.3048)
			(stroke
				(width 0.1)
				(type default)
			)
			(layer "B.Fab")
		)
		(fp_line
			(start -0.67945 -0.3048)
			(end -0.67945 0.3048)
			(stroke
				(width 0.1)
				(type default)
			)
			(layer "B.Fab")
		)
		(fp_line
			(start 0.12065 -0.2794)
			(end -0.12065 -0.2794)
			(stroke
				(width 0.1)
				(type default)
			)
			(layer "B.Fab")
		)
		(fp_line
			(start -0.12065 -0.2794)
			(end -0.12065 -0.3048)
			(stroke
				(width 0.1)
				(type default)
			)
			(layer "B.Fab")
		)
		(fp_line
			(start 0.12065 0.2794)
			(end 0.12065 0.3048)
			(stroke
				(width 0.1)
				(type default)
			)
			(layer "B.Fab")
		)
		(fp_line
			(start -0.120396 0.2794)
			(end 0.12065 0.2794)
			(stroke
				(width 0.1)
				(type default)
			)
			(layer "B.Fab")
		)
		(fp_line
			(start 0.67945 0.3048)
			(end 0.67945 -0.305054)
			(stroke
				(width 0.1)
				(type default)
			)
			(layer "B.Fab")
		)
		(fp_line
			(start 0.12065 0.3048)
			(end 0.67945 0.3048)
			(stroke
				(width 0.1)
				(type default)
			)
			(layer "B.Fab")
		)
		(fp_line
			(start -0.120396 0.3048)
			(end -0.120396 0.2794)
			(stroke
				(width 0.1)
				(type default)
			)
			(layer "B.Fab")
		)
		(fp_line
			(start -0.67945 0.3048)
			(end -0.120396 0.3048)
			(stroke
				(width 0.1)
				(type default)
			)
			(layer "B.Fab")
		)
		(pad "1" smd circle
			(at 0.40005 0 270)
			(size 0 0)
			(layers "B.Cu" "B.Mask" "B.Paste")
			(net "PVNN_TERM_CPU0")
		)
		(pad "2" smd circle
			(at -0.40005 0 270)
			(size 0 0)
			(layers "B.Cu" "B.Mask" "B.Paste")
			(net "JTAG_CPU0_MUX_GTL_TDO")
		)
	)
	(footprint ""
		(layer "B.Cu")
		(at 239.615726 -128.670812 90)
		(property "Reference" "R108"
			(at 0 0 90)
			(layer "B.SilkS")
			(hide yes)
			(effects
				(font
					(size 1.27 1.27)
				)
				(justify mirror)
			)
		)
		(property "Value" ""
			(at 0 0 90)
			(layer "B.Fab")
			(effects
				(font
					(size 1.27 1.27)
				)
				(justify mirror)
			)
		)
		(duplicate_pad_numbers_are_jumpers no)
		(fp_line
			(start 0.7874 -0.4064)
			(end -0.7874 -0.4064)
			(stroke
				(width 0.1524)
				(type default)
			)
			(layer "B.SilkS")
		)
		(fp_line
			(start -0.7874 -0.4064)
			(end -0.7874 0.4064)
			(stroke
				(width 0.1524)
				(type default)
			)
			(layer "B.SilkS")
		)
		(fp_line
			(start 0.7874 0.4064)
			(end 0.7874 -0.4064)
			(stroke
				(width 0.1524)
				(type default)
			)
			(layer "B.SilkS")
		)
		(fp_line
			(start -0.7874 0.4064)
			(end 0.7874 0.4064)
			(stroke
				(width 0.1524)
				(type default)
			)
			(layer "B.SilkS")
		)
		(fp_line
			(start 0.67945 -0.305054)
			(end 0.12065 -0.305054)
			(stroke
				(width 0.1)
				(type default)
			)
			(layer "B.Fab")
		)
		(fp_line
			(start 0.12065 -0.305054)
			(end 0.12065 -0.2794)
			(stroke
				(width 0.1)
				(type default)
			)
			(layer "B.Fab")
		)
		(fp_line
			(start -0.12065 -0.3048)
			(end -0.67945 -0.3048)
			(stroke
				(width 0.1)
				(type default)
			)
			(layer "B.Fab")
		)
		(fp_line
			(start -0.67945 -0.3048)
			(end -0.67945 0.3048)
			(stroke
				(width 0.1)
				(type default)
			)
			(layer "B.Fab")
		)
		(fp_line
			(start 0.12065 -0.2794)
			(end -0.12065 -0.2794)
			(stroke
				(width 0.1)
				(type default)
			)
			(layer "B.Fab")
		)
		(fp_line
			(start -0.12065 -0.2794)
			(end -0.12065 -0.3048)
			(stroke
				(width 0.1)
				(type default)
			)
			(layer "B.Fab")
		)
		(fp_line
			(start 0.12065 0.2794)
			(end 0.12065 0.3048)
			(stroke
				(width 0.1)
				(type default)
			)
			(layer "B.Fab")
		)
		(fp_line
			(start -0.120396 0.2794)
			(end 0.12065 0.2794)
			(stroke
				(width 0.1)
				(type default)
			)
			(layer "B.Fab")
		)
		(fp_line
			(start 0.67945 0.3048)
			(end 0.67945 -0.305054)
			(stroke
				(width 0.1)
				(type default)
			)
			(layer "B.Fab")
		)
		(fp_line
			(start 0.12065 0.3048)
			(end 0.67945 0.3048)
			(stroke
				(width 0.1)
				(type default)
			)
			(layer "B.Fab")
		)
		(fp_line
			(start -0.120396 0.3048)
			(end -0.120396 0.2794)
			(stroke
				(width 0.1)
				(type default)
			)
			(layer "B.Fab")
		)
		(fp_line
			(start -0.67945 0.3048)
			(end -0.120396 0.3048)
			(stroke
				(width 0.1)
				(type default)
			)
			(layer "B.Fab")
		)
		(pad "1" smd circle
			(at 0.40005 0 270)
			(size 0 0)
			(layers "B.Cu" "B.Mask" "B.Paste")
			(net "SMB_HOST_3V3AUX_SDA_R")
		)
		(pad "2" smd circle
			(at -0.40005 0 270)
			(size 0 0)
			(layers "B.Cu" "B.Mask" "B.Paste")
			(net "SMB_HOST_CLK_BUF_3V3AUX_SDA")
		)
	)
	(footprint ""
		(layer "B.Cu")
		(at 436.926482 -317.848996 90)
		(property "Reference" "R3888"
			(at 0 0 90)
			(layer "B.SilkS")
			(hide yes)
			(effects
				(font
					(size 1.27 1.27)
				)
				(justify mirror)
			)
		)
		(property "Value" ""
			(at 0 0 90)
			(layer "B.Fab")
			(effects
				(font
					(size 1.27 1.27)
				)
				(justify mirror)
			)
		)
		(duplicate_pad_numbers_are_jumpers no)
		(fp_line
			(start 0.7874 -0.4064)
			(end -0.7874 -0.4064)
			(stroke
				(width 0.1524)
				(type default)
			)
			(layer "B.SilkS")
		)
		(fp_line
			(start -0.7874 -0.4064)
			(end -0.7874 0.4064)
			(stroke
				(width 0.1524)
				(type default)
			)
			(layer "B.SilkS")
		)
		(fp_line
			(start 0.7874 0.4064)
			(end 0.7874 -0.4064)
			(stroke
				(width 0.1524)
				(type default)
			)
			(layer "B.SilkS")
		)
		(fp_line
			(start -0.7874 0.4064)
			(end 0.7874 0.4064)
			(stroke
				(width 0.1524)
				(type default)
			)
			(layer "B.SilkS")
		)
		(fp_line
			(start 0.67945 -0.305054)
			(end 0.12065 -0.305054)
			(stroke
				(width 0.1)
				(type default)
			)
			(layer "B.Fab")
		)
		(fp_line
			(start 0.12065 -0.305054)
			(end 0.12065 -0.2794)
			(stroke
				(width 0.1)
				(type default)
			)
			(layer "B.Fab")
		)
		(fp_line
			(start -0.12065 -0.3048)
			(end -0.67945 -0.3048)
			(stroke
				(width 0.1)
				(type default)
			)
			(layer "B.Fab")
		)
		(fp_line
			(start -0.67945 -0.3048)
			(end -0.67945 0.3048)
			(stroke
				(width 0.1)
				(type default)
			)
			(layer "B.Fab")
		)
		(fp_line
			(start 0.12065 -0.2794)
			(end -0.12065 -0.2794)
			(stroke
				(width 0.1)
				(type default)
			)
			(layer "B.Fab")
		)
		(fp_line
			(start -0.12065 -0.2794)
			(end -0.12065 -0.3048)
			(stroke
				(width 0.1)
				(type default)
			)
			(layer "B.Fab")
		)
		(fp_line
			(start 0.12065 0.2794)
			(end 0.12065 0.3048)
			(stroke
				(width 0.1)
				(type default)
			)
			(layer "B.Fab")
		)
		(fp_line
			(start -0.120396 0.2794)
			(end 0.12065 0.2794)
			(stroke
				(width 0.1)
				(type default)
			)
			(layer "B.Fab")
		)
		(fp_line
			(start 0.67945 0.3048)
			(end 0.67945 -0.305054)
			(stroke
				(width 0.1)
				(type default)
			)
			(layer "B.Fab")
		)
		(fp_line
			(start 0.12065 0.3048)
			(end 0.67945 0.3048)
			(stroke
				(width 0.1)
				(type default)
			)
			(layer "B.Fab")
		)
		(fp_line
			(start -0.120396 0.3048)
			(end -0.120396 0.2794)
			(stroke
				(width 0.1)
				(type default)
			)
			(layer "B.Fab")
		)
		(fp_line
			(start -0.67945 0.3048)
			(end -0.120396 0.3048)
			(stroke
				(width 0.1)
				(type default)
			)
			(layer "B.Fab")
		)
		(pad "1" smd circle
			(at 0.40005 0 270)
			(size 0 0)
			(layers "B.Cu" "B.Mask" "B.Paste")
			(net "I3C_SPD_DDREFGH_CPU0_LVC1_SCL_5")
		)
		(pad "2" smd circle
			(at -0.40005 0 270)
			(size 0 0)
			(layers "B.Cu" "B.Mask" "B.Paste")
			(net "I3C_SPD_DDREFGH_CPU0_LVC1_SCL")
		)
	)
	(footprint ""
		(layer "B.Cu")
		(at 75.460098 -184.255918 -90)
		(property "Reference" "R262"
			(at 0 0 90)
			(layer "B.SilkS")
			(hide yes)
			(effects
				(font
					(size 1.27 1.27)
				)
				(justify mirror)
			)
		)
		(property "Value" ""
			(at 0 0 90)
			(layer "B.Fab")
			(effects
				(font
					(size 1.27 1.27)
				)
				(justify mirror)
			)
		)
		(duplicate_pad_numbers_are_jumpers no)
		(fp_line
			(start -0.7874 0.4064)
			(end 0.7874 0.4064)
			(stroke
				(width 0.1524)
				(type default)
			)
			(layer "B.SilkS")
		)
		(fp_line
			(start 0.7874 0.4064)
			(end 0.7874 -0.4064)
			(stroke
				(width 0.1524)
				(type default)
			)
			(layer "B.SilkS")
		)
		(fp_line
			(start -0.7874 -0.4064)
			(end -0.7874 0.4064)
			(stroke
				(width 0.1524)
				(type default)
			)
			(layer "B.SilkS")
		)
		(fp_line
			(start 0.7874 -0.4064)
			(end -0.7874 -0.4064)
			(stroke
				(width 0.1524)
				(type default)
			)
			(layer "B.SilkS")
		)
		(fp_line
			(start -0.67945 0.3048)
			(end -0.120396 0.3048)
			(stroke
				(width 0.1)
				(type default)
			)
			(layer "B.Fab")
		)
		(fp_line
			(start -0.120396 0.3048)
			(end -0.120396 0.2794)
			(stroke
				(width 0.1)
				(type default)
			)
			(layer "B.Fab")
		)
		(fp_line
			(start 0.12065 0.3048)
			(end 0.67945 0.3048)
			(stroke
				(width 0.1)
				(type default)
			)
			(layer "B.Fab")
		)
		(fp_line
			(start 0.67945 0.3048)
			(end 0.67945 -0.305054)
			(stroke
				(width 0.1)
				(type default)
			)
			(layer "B.Fab")
		)
		(fp_line
			(start -0.120396 0.2794)
			(end 0.12065 0.2794)
			(stroke
				(width 0.1)
				(type default)
			)
			(layer "B.Fab")
		)
		(fp_line
			(start 0.12065 0.2794)
			(end 0.12065 0.3048)
			(stroke
				(width 0.1)
				(type default)
			)
			(layer "B.Fab")
		)
		(fp_line
			(start -0.12065 -0.2794)
			(end -0.12065 -0.3048)
			(stroke
				(width 0.1)
				(type default)
			)
			(layer "B.Fab")
		)
		(fp_line
			(start 0.12065 -0.2794)
			(end -0.12065 -0.2794)
			(stroke
				(width 0.1)
				(type default)
			)
			(layer "B.Fab")
		)
		(fp_line
			(start -0.67945 -0.3048)
			(end -0.67945 0.3048)
			(stroke
				(width 0.1)
				(type default)
			)
			(layer "B.Fab")
		)
		(fp_line
			(start -0.12065 -0.3048)
			(end -0.67945 -0.3048)
			(stroke
				(width 0.1)
				(type default)
			)
			(layer "B.Fab")
		)
		(fp_line
			(start 0.12065 -0.305054)
			(end 0.12065 -0.2794)
			(stroke
				(width 0.1)
				(type default)
			)
			(layer "B.Fab")
		)
		(fp_line
			(start 0.67945 -0.305054)
			(end 0.12065 -0.305054)
			(stroke
				(width 0.1)
				(type default)
			)
			(layer "B.Fab")
		)
		(pad "1" smd circle
			(at 0.40005 0 90)
			(size 0 0)
			(layers "B.Cu" "B.Mask" "B.Paste")
			(net "PVNN_TERM_CPU1")
		)
		(pad "2" smd circle
			(at -0.40005 0 90)
			(size 0 0)
			(layers "B.Cu" "B.Mask" "B.Paste")
			(net "PU_CPU1_SAFE_MODE_BOOT")
		)
	)
)
